FILE_TYPE=LIBRARY_PARTS;
primitive 'SCHOTTKY_12';
  pin
    'A':
      PIN_NUMBER='(1)';
      INPUT_LOAD='(-0.01,0.01)';
    'C':
      PIN_NUMBER='(2)';
      BIDIRECTIONAL='TRUE';
      INPUT_LOAD='(-0.01,0.01)';
      OUTPUT_LOAD='(1.0,-1.0)';
  end_pin;
  body
    PART_NAME='SCHOTTKY_12';
    BODY_NAME='SCHOTTKY_12';
    PHYS_DES_PREFIX='D';
    CLASS='DISCRETE';
  end_body;
end_primitive;

END.
